# BASEBOARD_FAB2 (Tioga Pass) — schematic netlist excerpt (pin names and nets, part order shuffled) for the footprints in the layout excerpt that follows; sources: Cadence DE-HDL packaged netlist, KiCad conversion of Wiwynn_Tioga_Pass_MB.brd

R8B29  RES  49.9 1% CHIP  pkg 0402  page 178 : A = SGPIO_PCH_SSATA_DOUT0 ; B = SGPIO_PCH_SSATA_DOUT0_R
C9F23  CAP_A  0.1UF 16V 10% X7R  pkg 0402V  page 145 : A = P3V3_STBY ; B = GND
C2A4  CAP_A  47UF 4V 20% X5R  pkg 0603V  page 228 : A = PVDDQ_KLM ; B = GND

(kicad_pcb
	(version 20260206)
	(generator "pcbnew")
	(generator_version "10.0")
	(general
		(thickness 1.6)
		(legacy_teardrops no)
	)
	(paper "A4")
	(title_block
		(title "Wiwynn_Tioga_Pass_MB.brd")
		(comment 1 "Tioga Pass / footprints 1083-1085 of 4770")
	)
	(layers
		(0 "F.Cu" signal "TOP")
		(4 "In1.Cu" signal "L2GND")
		(6 "In2.Cu" signal "L3")
		(8 "In3.Cu" signal "L4GND")
		(10 "In4.Cu" signal "L5")
		(12 "In5.Cu" signal "L6GND")
		(14 "In6.Cu" signal "L7VCC")
		(16 "In7.Cu" signal "L8VCC")
		(18 "In8.Cu" signal "L9GND")
		(20 "In9.Cu" signal "L10")
		(22 "In10.Cu" signal "L11GND")
		(24 "In11.Cu" signal "L12")
		(26 "In12.Cu" signal "L13GND")
		(2 "B.Cu" signal "BOTTOM")
		(9 "F.Adhes" user "F.Adhesive")
		(11 "B.Adhes" user "B.Adhesive")
		(13 "F.Paste" user "Package Geometry/Pastemask Top")
		(15 "B.Paste" user "Package Geometry/Pastemask Bottom")
		(5 "F.SilkS" user "Ref Des/Silkscreen Top")
		(7 "B.SilkS" user "Ref Des/Silkscreen Bottom")
		(1 "F.Mask" user "Board Geometry/Soldermask Top")
		(3 "B.Mask" user "Board Geometry/Soldermask Bottom")
		(17 "Dwgs.User" user "User.Drawings")
		(19 "Cmts.User" user "User.Comments")
		(21 "Eco1.User" user "User.Eco1")
		(23 "Eco2.User" user "User.Eco2")
		(25 "Edge.Cuts" user "Board Geometry/Outline")
		(27 "Margin" user)
		(31 "F.CrtYd" user "Package Geometry/Place Bound Top")
		(29 "B.CrtYd" user "Package Geometry/Place Bound Bottom")
		(35 "F.Fab" user "Ref Des/Assembly Top")
		(33 "B.Fab" user "Ref Des/Assembly Bottom")
	)
	(footprint ""
		(layer "F.Cu")
		(at 431.734468 -50.482246 90)
		(property "Reference" "C9F23"
			(at 0 0 90)
			(layer "F.SilkS")
			(hide yes)
			(effects
				(font
					(size 1.27 1.27)
				)
			)
		)
		(property "Value" ""
			(at 0 0 90)
			(layer "F.Fab")
			(effects
				(font
					(size 1.27 1.27)
				)
			)
		)
		(duplicate_pad_numbers_are_jumpers no)
		(fp_poly
			(pts
				(xy 0.3048 -0.1016) (xy 0.3048 0.9906) (xy -0.3048 0.9906) (xy -0.3048 -0.1016)
			)
			(stroke
				(width 0)
				(type default)
			)
			(fill no)
			(layer "F.CrtYd")
		)
		(fp_line
			(start 0.3048 -0.1016)
			(end -0.3048 -0.1016)
			(stroke
				(width 0.1)
				(type default)
			)
			(layer "F.Fab")
		)
		(fp_line
			(start -0.3048 -0.1016)
			(end -0.3048 0.9906)
			(stroke
				(width 0.1)
				(type default)
			)
			(layer "F.Fab")
		)
		(fp_line
			(start 0.3048 0.9906)
			(end 0.3048 -0.1016)
			(stroke
				(width 0.1)
				(type default)
			)
			(layer "F.Fab")
		)
		(fp_line
			(start -0.3048 0.9906)
			(end 0.3048 0.9906)
			(stroke
				(width 0.1)
				(type default)
			)
			(layer "F.Fab")
		)
		(pad "1" smd rect
			(at 0 0 90)
			(size 0.508 0.508)
			(layers "F.Cu" "F.Mask" "F.Paste")
			(net "P3V3_STBY")
		)
		(pad "2" smd rect
			(at 0 0.889 90)
			(size 0.508 0.508)
			(layers "F.Cu" "F.Mask" "F.Paste")
			(net "GND")
		)
		(zone
			(layer "F.Cu")
			(hatch none 0.5)
			(connect_pads
				(clearance 0)
			)
			(min_thickness 0.25)
			(keepout
				(tracks allowed)
				(vias not_allowed)
				(pads allowed)
				(copperpour not_allowed)
				(footprints allowed)
			)
			(placement
				(enabled no)
				(sheetname "")
			)
			(fill
				(thermal_gap 0.5)
				(thermal_bridge_width 0.5)
				(island_removal_mode 0)
			)
			(polygon
				(pts
					(xy 431.988468 -50.228246) (xy 431.988468 -50.736246) (xy 432.369468 -50.736246) (xy 432.369468 -50.228246)
				)
			)
		)
		(zone
			(layer "F.Cu")
			(hatch none 0.5)
			(connect_pads
				(clearance 0)
			)
			(min_thickness 0.25)
			(keepout
				(tracks not_allowed)
				(vias allowed)
				(pads allowed)
				(copperpour not_allowed)
				(footprints allowed)
			)
			(placement
				(enabled no)
				(sheetname "")
			)
			(fill
				(thermal_gap 0.5)
				(thermal_bridge_width 0.5)
				(island_removal_mode 0)
			)
			(polygon
				(pts
					(xy 432.369468 -50.228246) (xy 432.369468 -50.736246) (xy 431.988468 -50.736246) (xy 431.988468 -50.228246)
				)
			)
		)
	)
	(footprint ""
		(layer "F.Cu")
		(at 409.6512 -114.3 90)
		(property "Reference" "R8B29"
			(at 0 0 90)
			(layer "F.SilkS")
			(hide yes)
			(effects
				(font
					(size 1.27 1.27)
				)
			)
		)
		(property "Value" ""
			(at 0 0 90)
			(layer "F.Fab")
			(effects
				(font
					(size 1.27 1.27)
				)
			)
		)
		(duplicate_pad_numbers_are_jumpers no)
		(fp_poly
			(pts
				(xy -0.2794 -0.1016) (xy 0.2794 -0.1016) (xy 0.2794 0.9906) (xy -0.2794 0.9906)
			)
			(stroke
				(width 0)
				(type default)
			)
			(fill no)
			(layer "F.CrtYd")
		)
		(fp_line
			(start 0.2794 -0.1016)
			(end -0.2794 -0.1016)
			(stroke
				(width 0.1)
				(type default)
			)
			(layer "F.Fab")
		)
		(fp_line
			(start -0.2794 -0.1016)
			(end -0.2794 0.9906)
			(stroke
				(width 0.1)
				(type default)
			)
			(layer "F.Fab")
		)
		(fp_line
			(start 0.2794 0.9906)
			(end 0.2794 -0.1016)
			(stroke
				(width 0.1)
				(type default)
			)
			(layer "F.Fab")
		)
		(fp_line
			(start -0.2794 0.9906)
			(end 0.2794 0.9906)
			(stroke
				(width 0.1)
				(type default)
			)
			(layer "F.Fab")
		)
		(pad "1" smd rect
			(at 0 0 90)
			(size 0.508 0.508)
			(layers "F.Cu" "F.Mask" "F.Paste")
			(net "SGPIO_PCH_SSATA_DOUT0")
		)
		(pad "2" smd rect
			(at 0 0.889 90)
			(size 0.508 0.508)
			(layers "F.Cu" "F.Mask" "F.Paste")
			(net "SGPIO_PCH_SSATA_DOUT0_R")
		)
		(zone
			(layer "F.Cu")
			(hatch none 0.5)
			(connect_pads
				(clearance 0)
			)
			(min_thickness 0.25)
			(keepout
				(tracks allowed)
				(vias not_allowed)
				(pads allowed)
				(copperpour not_allowed)
				(footprints allowed)
			)
			(placement
				(enabled no)
				(sheetname "")
			)
			(fill
				(thermal_gap 0.5)
				(thermal_bridge_width 0.5)
				(island_removal_mode 0)
			)
			(polygon
				(pts
					(xy 409.9052 -114.046) (xy 409.9052 -114.554) (xy 410.2862 -114.554) (xy 410.2862 -114.046)
				)
			)
		)
		(zone
			(layer "F.Cu")
			(hatch none 0.5)
			(connect_pads
				(clearance 0)
			)
			(min_thickness 0.25)
			(keepout
				(tracks not_allowed)
				(vias allowed)
				(pads allowed)
				(copperpour not_allowed)
				(footprints allowed)
			)
			(placement
				(enabled no)
				(sheetname "")
			)
			(fill
				(thermal_gap 0.5)
				(thermal_bridge_width 0.5)
				(island_removal_mode 0)
			)
			(polygon
				(pts
					(xy 410.2862 -114.046) (xy 410.2862 -114.554) (xy 409.9052 -114.554) (xy 409.9052 -114.046)
				)
			)
		)
	)
	(footprint ""
		(layer "F.Cu")
		(at 88.392 -149.8092 90)
		(property "Reference" "C2A4"
			(at 1.848866 0.752348 90)
			(unlocked yes)
			(layer "F.SilkS")
			(effects
				(font
					(size 1.27 0.9652)
					(thickness 0.1524)
				)
			)
		)
		(property "Value" ""
			(at 0 0 90)
			(layer "F.Fab")
			(effects
				(font
					(size 1.27 1.27)
				)
			)
		)
		(duplicate_pad_numbers_are_jumpers no)
		(fp_rect
			(start -0.500126 1.598422)
			(end 0.500126 -0.201422)
			(stroke
				(width 0)
				(type default)
			)
			(fill no)
			(layer "F.CrtYd")
		)
		(fp_line
			(start 0.500126 -0.201422)
			(end 0.500126 1.598422)
			(stroke
				(width 0.1)
				(type default)
			)
			(layer "F.Fab")
		)
		(fp_line
			(start -0.500126 -0.201422)
			(end 0.500126 -0.201422)
			(stroke
				(width 0.1)
				(type default)
			)
			(layer "F.Fab")
		)
		(fp_line
			(start 0.500126 1.598422)
			(end -0.500126 1.598422)
			(stroke
				(width 0.1)
				(type default)
			)
			(layer "F.Fab")
		)
		(fp_line
			(start -0.500126 1.598422)
			(end -0.500126 -0.201422)
			(stroke
				(width 0.1)
				(type default)
			)
			(layer "F.Fab")
		)
		(pad "1" smd rect
			(at 0 0)
			(size 0.889 0.9906)
			(layers "F.Cu" "F.Mask" "F.Paste")
			(net "PVDDQ_KLM")
		)
		(pad "2" smd rect
			(at 0 1.397)
			(size 0.889 0.9906)
			(layers "F.Cu" "F.Mask" "F.Paste")
			(net "GND")
		)
		(zone
			(layer "F.Cu")
			(hatch none 0.5)
			(connect_pads
				(clearance 0)
			)
			(min_thickness 0.25)
			(keepout
				(tracks allowed)
				(vias not_allowed)
				(pads allowed)
				(copperpour not_allowed)
				(footprints allowed)
			)
			(placement
				(enabled no)
				(sheetname "")
			)
			(fill
				(thermal_gap 0.5)
				(thermal_bridge_width 0.5)
				(island_removal_mode 0)
			)
			(polygon
				(pts
					(xy 89.3445 -149.3139) (xy 89.3445 -150.3045) (xy 88.8365 -150.3045) (xy 88.8365 -149.3139)
				)
			)
		)
		(zone
			(layer "F.Cu")
			(hatch none 0.5)
			(connect_pads
				(clearance 0)
			)
			(min_thickness 0.25)
			(keepout
				(tracks not_allowed)
				(vias allowed)
				(pads allowed)
				(copperpour not_allowed)
				(footprints allowed)
			)
			(placement
				(enabled no)
				(sheetname "")
			)
			(fill
				(thermal_gap 0.5)
				(thermal_bridge_width 0.5)
				(island_removal_mode 0)
			)
			(polygon
				(pts
					(xy 89.3445 -149.3139) (xy 89.3445 -150.3045) (xy 88.8365 -150.3045) (xy 88.8365 -149.3139)
				)
			)
		)
	)
)
